# S9S_MB_2U (Grand Teton) — schematic netlist excerpt (pin names and nets, part order shuffled) for the footprints in the layout excerpt that follows; sources: Cadence DE-HDL packaged netlist, KiCad conversion of 03242023_DA0F0TMBIJ0_F0T_Motherboard_J_brd_V01_OCP.brd

PC568  Q_CAP  0.22UF 25V 10% X7R  pkg C0402  page 259 : A = SW_P3V3_AUX_BOOTR ; B = SW_P3V3_AUX_BOOT_R
R981  Q_RES  33.2 1% CHIP  pkg 0402LF  page 222 : A = FM_PVCCIN_CPU0_R_EN ; B = FM_PVCCIN_CPU0_EN

(kicad_pcb
	(version 20260206)
	(generator "pcbnew")
	(generator_version "10.0")
	(general
		(thickness 1.6)
		(legacy_teardrops no)
	)
	(paper "A4")
	(title_block
		(title "03242023_DA0F0TMBIJ0_F0T_Motherboard_J_brd_V01_OCP.brd")
		(comment 1 "Grand Teton / footprints 2561-2562 of 6105")
	)
	(layers
		(0 "F.Cu" signal "TOP")
		(4 "In1.Cu" signal "GND")
		(6 "In2.Cu" signal "IN1")
		(8 "In3.Cu" signal "GND1")
		(10 "In4.Cu" signal "IN2")
		(12 "In5.Cu" signal "GND2")
		(14 "In6.Cu" signal "IN3")
		(16 "In7.Cu" signal "GND3")
		(18 "In8.Cu" signal "VCC")
		(20 "In9.Cu" signal "VCC1")
		(22 "In10.Cu" signal "GND4")
		(24 "In11.Cu" signal "IN4")
		(26 "In12.Cu" signal "GND5")
		(28 "In13.Cu" signal "IN5")
		(30 "In14.Cu" signal "GND6")
		(32 "In15.Cu" signal "IN6")
		(34 "In16.Cu" signal "GND7")
		(2 "B.Cu" signal "BOTTOM")
		(9 "F.Adhes" user "F.Adhesive")
		(11 "B.Adhes" user "B.Adhesive")
		(13 "F.Paste" user "Package Geometry/Pastemask Top")
		(15 "B.Paste" user "Package Geometry/Pastemask Bottom")
		(5 "F.SilkS" user "Ref Des/Silkscreen Top")
		(7 "B.SilkS" user "Ref Des/Silkscreen Bottom")
		(1 "F.Mask" user "Board Geometry/Soldermask Top")
		(3 "B.Mask" user "Board Geometry/Soldermask Bottom")
		(17 "Dwgs.User" user "User.Drawings")
		(19 "Cmts.User" user "User.Comments")
		(21 "Eco1.User" user "User.Eco1")
		(23 "Eco2.User" user "User.Eco2")
		(25 "Edge.Cuts" user "Board Geometry/Outline")
		(27 "Margin" user)
		(31 "F.CrtYd" user "Package Geometry/Place Bound Top")
		(29 "B.CrtYd" user "Package Geometry/Place Bound Bottom")
		(35 "F.Fab" user "Ref Des/Assembly Top")
		(33 "B.Fab" user "Ref Des/Assembly Bottom")
	)
	(footprint ""
		(layer "F.Cu")
		(at 452.482712 -74.136504)
		(property "Reference" "PC568"
			(at 0 0 0)
			(layer "F.SilkS")
			(hide yes)
			(effects
				(font
					(size 1.27 1.27)
				)
			)
		)
		(property "Value" ""
			(at 0 0 0)
			(layer "F.Fab")
			(effects
				(font
					(size 1.27 1.27)
				)
			)
		)
		(duplicate_pad_numbers_are_jumpers no)
		(fp_line
			(start -0.7874 -0.4064)
			(end 0.7874 -0.4064)
			(stroke
				(width 0.1524)
				(type default)
			)
			(layer "F.SilkS")
		)
		(fp_line
			(start -0.7874 0.4064)
			(end -0.7874 -0.4064)
			(stroke
				(width 0.1524)
				(type default)
			)
			(layer "F.SilkS")
		)
		(fp_line
			(start 0.7874 -0.4064)
			(end 0.7874 0.4064)
			(stroke
				(width 0.1524)
				(type default)
			)
			(layer "F.SilkS")
		)
		(fp_line
			(start 0.7874 0.4064)
			(end -0.7874 0.4064)
			(stroke
				(width 0.1524)
				(type default)
			)
			(layer "F.SilkS")
		)
		(fp_line
			(start -0.67945 -0.305054)
			(end -0.12065 -0.305054)
			(stroke
				(width 0.1)
				(type default)
			)
			(layer "F.Fab")
		)
		(fp_line
			(start -0.67945 0.3048)
			(end -0.67945 -0.305054)
			(stroke
				(width 0.1)
				(type default)
			)
			(layer "F.Fab")
		)
		(fp_line
			(start -0.12065 -0.305054)
			(end -0.12065 -0.2794)
			(stroke
				(width 0.1)
				(type default)
			)
			(layer "F.Fab")
		)
		(fp_line
			(start -0.12065 -0.2794)
			(end 0.12065 -0.2794)
			(stroke
				(width 0.1)
				(type default)
			)
			(layer "F.Fab")
		)
		(fp_line
			(start -0.12065 0.2794)
			(end -0.12065 0.3048)
			(stroke
				(width 0.1)
				(type default)
			)
			(layer "F.Fab")
		)
		(fp_line
			(start -0.12065 0.3048)
			(end -0.67945 0.3048)
			(stroke
				(width 0.1)
				(type default)
			)
			(layer "F.Fab")
		)
		(fp_line
			(start 0.120396 0.2794)
			(end -0.12065 0.2794)
			(stroke
				(width 0.1)
				(type default)
			)
			(layer "F.Fab")
		)
		(fp_line
			(start 0.120396 0.3048)
			(end 0.120396 0.2794)
			(stroke
				(width 0.1)
				(type default)
			)
			(layer "F.Fab")
		)
		(fp_line
			(start 0.12065 -0.3048)
			(end 0.67945 -0.3048)
			(stroke
				(width 0.1)
				(type default)
			)
			(layer "F.Fab")
		)
		(fp_line
			(start 0.12065 -0.2794)
			(end 0.12065 -0.3048)
			(stroke
				(width 0.1)
				(type default)
			)
			(layer "F.Fab")
		)
		(fp_line
			(start 0.67945 -0.3048)
			(end 0.67945 0.3048)
			(stroke
				(width 0.1)
				(type default)
			)
			(layer "F.Fab")
		)
		(fp_line
			(start 0.67945 0.3048)
			(end 0.120396 0.3048)
			(stroke
				(width 0.1)
				(type default)
			)
			(layer "F.Fab")
		)
		(pad "1" smd circle
			(at -0.40005 0)
			(size 0 0)
			(layers "F.Cu" "F.Mask" "F.Paste")
			(net "SW_P3V3_AUX_BOOTR")
		)
		(pad "2" smd circle
			(at 0.40005 0)
			(size 0 0)
			(layers "F.Cu" "F.Mask" "F.Paste")
			(net "SW_P3V3_AUX_BOOT_R")
		)
	)
	(footprint ""
		(layer "F.Cu")
		(at 157.02788 -121.376948 180)
		(property "Reference" "R981"
			(at 0 0 180)
			(layer "F.SilkS")
			(hide yes)
			(effects
				(font
					(size 1.27 1.27)
				)
			)
		)
		(property "Value" ""
			(at 0 0 180)
			(layer "F.Fab")
			(effects
				(font
					(size 1.27 1.27)
				)
			)
		)
		(duplicate_pad_numbers_are_jumpers no)
		(fp_line
			(start 0.7874 0.4064)
			(end -0.7874 0.4064)
			(stroke
				(width 0.1524)
				(type default)
			)
			(layer "F.SilkS")
		)
		(fp_line
			(start 0.7874 -0.4064)
			(end 0.7874 0.4064)
			(stroke
				(width 0.1524)
				(type default)
			)
			(layer "F.SilkS")
		)
		(fp_line
			(start -0.7874 0.4064)
			(end -0.7874 -0.4064)
			(stroke
				(width 0.1524)
				(type default)
			)
			(layer "F.SilkS")
		)
		(fp_line
			(start -0.7874 -0.4064)
			(end 0.7874 -0.4064)
			(stroke
				(width 0.1524)
				(type default)
			)
			(layer "F.SilkS")
		)
		(fp_line
			(start 0.67945 0.3048)
			(end 0.120396 0.3048)
			(stroke
				(width 0.1)
				(type default)
			)
			(layer "F.Fab")
		)
		(fp_line
			(start 0.67945 -0.3048)
			(end 0.67945 0.3048)
			(stroke
				(width 0.1)
				(type default)
			)
			(layer "F.Fab")
		)
		(fp_line
			(start 0.12065 -0.2794)
			(end 0.12065 -0.3048)
			(stroke
				(width 0.1)
				(type default)
			)
			(layer "F.Fab")
		)
		(fp_line
			(start 0.12065 -0.3048)
			(end 0.67945 -0.3048)
			(stroke
				(width 0.1)
				(type default)
			)
			(layer "F.Fab")
		)
		(fp_line
			(start 0.120396 0.3048)
			(end 0.120396 0.2794)
			(stroke
				(width 0.1)
				(type default)
			)
			(layer "F.Fab")
		)
		(fp_line
			(start 0.120396 0.2794)
			(end -0.12065 0.2794)
			(stroke
				(width 0.1)
				(type default)
			)
			(layer "F.Fab")
		)
		(fp_line
			(start -0.12065 0.3048)
			(end -0.67945 0.3048)
			(stroke
				(width 0.1)
				(type default)
			)
			(layer "F.Fab")
		)
		(fp_line
			(start -0.12065 0.2794)
			(end -0.12065 0.3048)
			(stroke
				(width 0.1)
				(type default)
			)
			(layer "F.Fab")
		)
		(fp_line
			(start -0.12065 -0.2794)
			(end 0.12065 -0.2794)
			(stroke
				(width 0.1)
				(type default)
			)
			(layer "F.Fab")
		)
		(fp_line
			(start -0.12065 -0.305054)
			(end -0.12065 -0.2794)
			(stroke
				(width 0.1)
				(type default)
			)
			(layer "F.Fab")
		)
		(fp_line
			(start -0.67945 0.3048)
			(end -0.67945 -0.305054)
			(stroke
				(width 0.1)
				(type default)
			)
			(layer "F.Fab")
		)
		(fp_line
			(start -0.67945 -0.305054)
			(end -0.12065 -0.305054)
			(stroke
				(width 0.1)
				(type default)
			)
			(layer "F.Fab")
		)
		(pad "1" smd circle
			(at -0.40005 0 180)
			(size 0 0)
			(layers "F.Cu" "F.Mask" "F.Paste")
			(net "FM_PVCCIN_CPU0_R_EN")
		)
		(pad "2" smd circle
			(at 0.40005 0 180)
			(size 0 0)
			(layers "F.Cu" "F.Mask" "F.Paste")
			(net "FM_PVCCIN_CPU0_EN")
		)
	)
)
